# S9S_MB_2U (Grand Teton) — schematic netlist excerpt (pin names and nets, part order shuffled) for the footprints in the layout excerpt that follows; sources: Cadence DE-HDL packaged netlist, KiCad conversion of 03242023_DA0F0TMBIJ0_F0T_Motherboard_J_brd_V01_OCP.brd

R3861  Q_RES  0 5% EMPTY  pkg 0402LF  page 250 : A = P12V_OCP_V3_2_ISENSE_MAM_TIC ; B = P12V_OCP_V3_2_ISENSE_TIC
R3794  Q_RES  0 5% CHIP  pkg 0402LF  page 156 : A = P3V3_OCP_PWRGD_1 ; B = OCP_V3_1_P3V3_PWRGD

(kicad_pcb
	(version 20260206)
	(generator "pcbnew")
	(generator_version "10.0")
	(general
		(thickness 1.6)
		(legacy_teardrops no)
	)
	(paper "A4")
	(title_block
		(title "03242023_DA0F0TMBIJ0_F0T_Motherboard_J_brd_V01_OCP.brd")
		(comment 1 "Grand Teton / footprints 1081-1082 of 6105")
	)
	(layers
		(0 "F.Cu" signal "TOP")
		(4 "In1.Cu" signal "GND")
		(6 "In2.Cu" signal "IN1")
		(8 "In3.Cu" signal "GND1")
		(10 "In4.Cu" signal "IN2")
		(12 "In5.Cu" signal "GND2")
		(14 "In6.Cu" signal "IN3")
		(16 "In7.Cu" signal "GND3")
		(18 "In8.Cu" signal "VCC")
		(20 "In9.Cu" signal "VCC1")
		(22 "In10.Cu" signal "GND4")
		(24 "In11.Cu" signal "IN4")
		(26 "In12.Cu" signal "GND5")
		(28 "In13.Cu" signal "IN5")
		(30 "In14.Cu" signal "GND6")
		(32 "In15.Cu" signal "IN6")
		(34 "In16.Cu" signal "GND7")
		(2 "B.Cu" signal "BOTTOM")
		(9 "F.Adhes" user "F.Adhesive")
		(11 "B.Adhes" user "B.Adhesive")
		(13 "F.Paste" user "Package Geometry/Pastemask Top")
		(15 "B.Paste" user "Package Geometry/Pastemask Bottom")
		(5 "F.SilkS" user "Ref Des/Silkscreen Top")
		(7 "B.SilkS" user "Ref Des/Silkscreen Bottom")
		(1 "F.Mask" user "Board Geometry/Soldermask Top")
		(3 "B.Mask" user "Board Geometry/Soldermask Bottom")
		(17 "Dwgs.User" user "User.Drawings")
		(19 "Cmts.User" user "User.Comments")
		(21 "Eco1.User" user "User.Eco1")
		(23 "Eco2.User" user "User.Eco2")
		(25 "Edge.Cuts" user "Board Geometry/Outline")
		(27 "Margin" user)
		(31 "F.CrtYd" user "Package Geometry/Place Bound Top")
		(29 "B.CrtYd" user "Package Geometry/Place Bound Bottom")
		(35 "F.Fab" user "Ref Des/Assembly Top")
		(33 "B.Fab" user "Ref Des/Assembly Bottom")
	)
	(footprint ""
		(layer "F.Cu")
		(at 39.827454 -110.587282)
		(property "Reference" "R3861"
			(at 0 0 0)
			(layer "F.SilkS")
			(hide yes)
			(effects
				(font
					(size 1.27 1.27)
				)
			)
		)
		(property "Value" ""
			(at 0 0 0)
			(layer "F.Fab")
			(effects
				(font
					(size 1.27 1.27)
				)
			)
		)
		(duplicate_pad_numbers_are_jumpers no)
		(fp_line
			(start -0.7874 -0.4064)
			(end 0.7874 -0.4064)
			(stroke
				(width 0.1524)
				(type default)
			)
			(layer "F.SilkS")
		)
		(fp_line
			(start -0.7874 0.4064)
			(end -0.7874 -0.4064)
			(stroke
				(width 0.1524)
				(type default)
			)
			(layer "F.SilkS")
		)
		(fp_line
			(start 0.7874 -0.4064)
			(end 0.7874 0.4064)
			(stroke
				(width 0.1524)
				(type default)
			)
			(layer "F.SilkS")
		)
		(fp_line
			(start 0.7874 0.4064)
			(end -0.7874 0.4064)
			(stroke
				(width 0.1524)
				(type default)
			)
			(layer "F.SilkS")
		)
		(fp_line
			(start -0.67945 -0.305054)
			(end -0.12065 -0.305054)
			(stroke
				(width 0.1)
				(type default)
			)
			(layer "F.Fab")
		)
		(fp_line
			(start -0.67945 0.3048)
			(end -0.67945 -0.305054)
			(stroke
				(width 0.1)
				(type default)
			)
			(layer "F.Fab")
		)
		(fp_line
			(start -0.12065 -0.305054)
			(end -0.12065 -0.2794)
			(stroke
				(width 0.1)
				(type default)
			)
			(layer "F.Fab")
		)
		(fp_line
			(start -0.12065 -0.2794)
			(end 0.12065 -0.2794)
			(stroke
				(width 0.1)
				(type default)
			)
			(layer "F.Fab")
		)
		(fp_line
			(start -0.12065 0.2794)
			(end -0.12065 0.3048)
			(stroke
				(width 0.1)
				(type default)
			)
			(layer "F.Fab")
		)
		(fp_line
			(start -0.12065 0.3048)
			(end -0.67945 0.3048)
			(stroke
				(width 0.1)
				(type default)
			)
			(layer "F.Fab")
		)
		(fp_line
			(start 0.120396 0.2794)
			(end -0.12065 0.2794)
			(stroke
				(width 0.1)
				(type default)
			)
			(layer "F.Fab")
		)
		(fp_line
			(start 0.120396 0.3048)
			(end 0.120396 0.2794)
			(stroke
				(width 0.1)
				(type default)
			)
			(layer "F.Fab")
		)
		(fp_line
			(start 0.12065 -0.3048)
			(end 0.67945 -0.3048)
			(stroke
				(width 0.1)
				(type default)
			)
			(layer "F.Fab")
		)
		(fp_line
			(start 0.12065 -0.2794)
			(end 0.12065 -0.3048)
			(stroke
				(width 0.1)
				(type default)
			)
			(layer "F.Fab")
		)
		(fp_line
			(start 0.67945 -0.3048)
			(end 0.67945 0.3048)
			(stroke
				(width 0.1)
				(type default)
			)
			(layer "F.Fab")
		)
		(fp_line
			(start 0.67945 0.3048)
			(end 0.120396 0.3048)
			(stroke
				(width 0.1)
				(type default)
			)
			(layer "F.Fab")
		)
		(pad "1" smd rect
			(at -0.40005 0 180)
			(size 0.4572 0.508)
			(layers "F.Cu" "F.Mask" "F.Paste")
			(net "P12V_OCP_V3_2_ISENSE_MAM_TIC")
		)
		(pad "2" smd rect
			(at 0.40005 0 180)
			(size 0.4572 0.508)
			(layers "F.Cu" "F.Mask" "F.Paste")
			(net "P12V_OCP_V3_2_ISENSE_TIC")
		)
	)
	(footprint ""
		(layer "F.Cu")
		(at 428.880016 -102.37724 -90)
		(property "Reference" "R3794"
			(at 0 0 270)
			(layer "F.SilkS")
			(hide yes)
			(effects
				(font
					(size 1.27 1.27)
				)
			)
		)
		(property "Value" ""
			(at 0 0 270)
			(layer "F.Fab")
			(effects
				(font
					(size 1.27 1.27)
				)
			)
		)
		(duplicate_pad_numbers_are_jumpers no)
		(fp_line
			(start -0.7874 0.4064)
			(end -0.7874 -0.4064)
			(stroke
				(width 0.1524)
				(type default)
			)
			(layer "F.SilkS")
		)
		(fp_line
			(start 0.7874 0.4064)
			(end -0.7874 0.4064)
			(stroke
				(width 0.1524)
				(type default)
			)
			(layer "F.SilkS")
		)
		(fp_line
			(start -0.7874 -0.4064)
			(end 0.7874 -0.4064)
			(stroke
				(width 0.1524)
				(type default)
			)
			(layer "F.SilkS")
		)
		(fp_line
			(start 0.7874 -0.4064)
			(end 0.7874 0.4064)
			(stroke
				(width 0.1524)
				(type default)
			)
			(layer "F.SilkS")
		)
		(fp_line
			(start -0.67945 0.3048)
			(end -0.67945 -0.305054)
			(stroke
				(width 0.1)
				(type default)
			)
			(layer "F.Fab")
		)
		(fp_line
			(start -0.12065 0.3048)
			(end -0.67945 0.3048)
			(stroke
				(width 0.1)
				(type default)
			)
			(layer "F.Fab")
		)
		(fp_line
			(start 0.120396 0.3048)
			(end 0.120396 0.2794)
			(stroke
				(width 0.1)
				(type default)
			)
			(layer "F.Fab")
		)
		(fp_line
			(start 0.67945 0.3048)
			(end 0.120396 0.3048)
			(stroke
				(width 0.1)
				(type default)
			)
			(layer "F.Fab")
		)
		(fp_line
			(start -0.12065 0.2794)
			(end -0.12065 0.3048)
			(stroke
				(width 0.1)
				(type default)
			)
			(layer "F.Fab")
		)
		(fp_line
			(start 0.120396 0.2794)
			(end -0.12065 0.2794)
			(stroke
				(width 0.1)
				(type default)
			)
			(layer "F.Fab")
		)
		(fp_line
			(start -0.12065 -0.2794)
			(end 0.12065 -0.2794)
			(stroke
				(width 0.1)
				(type default)
			)
			(layer "F.Fab")
		)
		(fp_line
			(start 0.12065 -0.2794)
			(end 0.12065 -0.3048)
			(stroke
				(width 0.1)
				(type default)
			)
			(layer "F.Fab")
		)
		(fp_line
			(start 0.12065 -0.3048)
			(end 0.67945 -0.3048)
			(stroke
				(width 0.1)
				(type default)
			)
			(layer "F.Fab")
		)
		(fp_line
			(start 0.67945 -0.3048)
			(end 0.67945 0.3048)
			(stroke
				(width 0.1)
				(type default)
			)
			(layer "F.Fab")
		)
		(fp_line
			(start -0.67945 -0.305054)
			(end -0.12065 -0.305054)
			(stroke
				(width 0.1)
				(type default)
			)
			(layer "F.Fab")
		)
		(fp_line
			(start -0.12065 -0.305054)
			(end -0.12065 -0.2794)
			(stroke
				(width 0.1)
				(type default)
			)
			(layer "F.Fab")
		)
		(pad "1" smd circle
			(at -0.40005 0 270)
			(size 0 0)
			(layers "F.Cu" "F.Mask" "F.Paste")
			(net "P3V3_OCP_PWRGD_1")
		)
		(pad "2" smd circle
			(at 0.40005 0 270)
			(size 0 0)
			(layers "F.Cu" "F.Mask" "F.Paste")
			(net "OCP_V3_1_P3V3_PWRGD")
		)
	)
)
